(kicad_pcb
	(version 20260206)
	(generator "pcbnew")
	(generator_version "10.0")
	(general
		(thickness 1.6)
		(legacy_teardrops no)
	)
	(paper "A4")
	(title_block
		(title "Bryce Canyon_F.DPB_16315-1-OCP.brd")
		(comment 1 "Bryce Canyon / footprints 727-729 of 2223")
	)
	(layers
		(0 "F.Cu" signal "TOP")
		(4 "In1.Cu" signal "L2GND")
		(6 "In2.Cu" signal "L3")
		(8 "In3.Cu" signal "L4GND")
		(10 "In4.Cu" signal "L5")
		(12 "In5.Cu" signal "L6VCC")
		(14 "In6.Cu" signal "L7VCC")
		(16 "In7.Cu" signal "L8")
		(18 "In8.Cu" signal "L9GND")
		(20 "In9.Cu" signal "L10")
		(22 "In10.Cu" signal "L11GND")
		(2 "B.Cu" signal "BOTTOM")
		(9 "F.Adhes" user "F.Adhesive")
		(11 "B.Adhes" user "B.Adhesive")
		(13 "F.Paste" user "Package Geometry/Pastemask Top")
		(15 "B.Paste" user "Package Geometry/Pastemask Bottom")
		(5 "F.SilkS" user "Ref Des/Silkscreen Top")
		(7 "B.SilkS" user "Ref Des/Silkscreen Bottom")
		(1 "F.Mask" user "Board Geometry/Soldermask Top")
		(3 "B.Mask" user "Board Geometry/Soldermask Bottom")
		(17 "Dwgs.User" user "User.Drawings")
		(19 "Cmts.User" user "User.Comments")
		(21 "Eco1.User" user "User.Eco1")
		(23 "Eco2.User" user "User.Eco2")
		(25 "Edge.Cuts" user "Board Geometry/Outline")
		(27 "Margin" user)
		(31 "F.CrtYd" user "Package Geometry/Place Bound Top")
		(29 "B.CrtYd" user "Package Geometry/Place Bound Bottom")
		(35 "F.Fab" user "Ref Des/Assembly Top")
		(33 "B.Fab" user "Ref Des/Assembly Bottom")
	)
	(footprint ""
		(layer "F.Cu")
		(at 388.649972 -287.910016 -90)
		(property "Reference" "HDDSAS8"
			(at 0 0 270)
			(layer "F.SilkS")
			(hide yes)
			(effects
				(font
					(size 1.27 1.27)
				)
			)
		)
		(property "Value" "SKT-SAS15P-14P-45-GP"
			(at -20.7645 -8.9789 270)
			(unlocked yes)
			(layer "F.Fab")
			(hide yes)
			(effects
				(font
					(size 1.016 1.016)
					(thickness 0.1524)
				)
			)
		)
		(property "Device Type" "10120818-001C-TRLF"
			(at -20.7645 -10.5029 270)
			(unlocked yes)
			(layer "F.Fab")
			(hide yes)
			(effects
				(font
					(size 1.016 1.016)
					(thickness 0.1524)
				)
			)
		)
		(duplicate_pad_numbers_are_jumpers no)
		(fp_line
			(start 1.651 4.2926)
			(end 1.651 3.0099)
			(stroke
				(width 0.1524)
				(type default)
			)
			(layer "F.SilkS")
		)
		(fp_line
			(start 8.509 4.2926)
			(end 1.651 4.2926)
			(stroke
				(width 0.1524)
				(type default)
			)
			(layer "F.SilkS")
		)
		(fp_line
			(start -23.4188 3.0099)
			(end -23.4188 -3.2512)
			(stroke
				(width 0.1524)
				(type default)
			)
			(layer "F.SilkS")
		)
		(fp_line
			(start 1.651 3.0099)
			(end -23.4188 3.0099)
			(stroke
				(width 0.1524)
				(type default)
			)
			(layer "F.SilkS")
		)
		(fp_line
			(start 8.509 3.0099)
			(end 8.509 4.2926)
			(stroke
				(width 0.1524)
				(type default)
			)
			(layer "F.SilkS")
		)
		(fp_line
			(start 23.4188 3.0099)
			(end 8.509 3.0099)
			(stroke
				(width 0.1524)
				(type default)
			)
			(layer "F.SilkS")
		)
		(fp_line
			(start -23.4188 -3.2512)
			(end 23.4188 -3.2512)
			(stroke
				(width 0.1524)
				(type default)
			)
			(layer "F.SilkS")
		)
		(fp_line
			(start 23.4188 -3.2512)
			(end 23.4188 3.0099)
			(stroke
				(width 0.1524)
				(type default)
			)
			(layer "F.SilkS")
		)
		(fp_line
			(start 15.5067 -3.3401)
			(end 16.2687 -3.3401)
			(stroke
				(width 0.3302)
				(type default)
			)
			(layer "F.SilkS")
		)
		(fp_poly
			(pts
				(xy 15.868904 -3.230372) (xy 16.503904 -3.865372) (xy 15.233904 -3.865372)
			)
			(stroke
				(width 0)
				(type default)
			)
			(fill yes)
			(layer "F.SilkS")
		)
		(fp_poly
			(pts
				(xy -22.8727 -2.7559) (xy 22.8727 -2.7559) (xy 22.8727 2.7559) (xy 8.255 2.7559) (xy 8.255 3.5179)
				(xy 1.905 3.5179) (xy 1.905 2.7559) (xy -22.8727 2.7559)
			)
			(stroke
				(width 0)
				(type default)
			)
			(fill no)
			(layer "F.CrtYd")
		)
		(fp_poly
			(pts
				(xy 1.397 4.5466) (xy 1.397 3.2639) (xy -23.6728 3.2639) (xy -23.6728 -3.5052) (xy 23.6728 -3.5052)
				(xy 23.6728 -0.00635) (xy 22.8727 -0.00635) (xy 22.8727 -2.7559) (xy -22.8727 -2.7559) (xy -22.8727 2.7559)
				(xy 1.905 2.7559) (xy 1.905 3.5179) (xy 8.255 3.5179) (xy 8.255 2.7559) (xy 22.8727 2.7559) (xy 22.8727 0.00635)
				(xy 23.6728 0.00635) (xy 23.6728 3.2639) (xy 8.763 3.2639) (xy 8.763 4.5466)
			)
			(stroke
				(width 0)
				(type default)
			)
			(fill no)
			(layer "F.CrtYd")
		)
		(fp_poly
			(pts
				(xy 1.397 4.5466) (xy 1.397 3.2639) (xy -23.6728 3.2639) (xy -23.6728 -3.5052) (xy 23.6728 -3.5052)
				(xy 23.6728 3.2639) (xy 8.763 3.2639) (xy 8.763 4.5466)
			)
			(stroke
				(width 0)
				(type default)
			)
			(fill no)
			(layer "F.Fab")
		)
		(pad "" np_thru_hole circle
			(at -18.874994 0 270)
			(size 0.254 0.254)
			(drill 1.3462)
			(layers "*.Cu" "*.Mask")
			(clearance 0.9017)
			(thermal_gap 0.9017)
		)
		(pad "" np_thru_hole circle
			(at 18.874994 0 270)
			(size 0.254 0.254)
			(drill 0.9398)
			(layers "*.Cu" "*.Mask")
			(clearance 0.6985)
			(thermal_gap 0.6985)
		)
		(pad "G1" smd rect
			(at 21.874988 0 270)
			(size 2.5908 2.5908)
			(layers "F.Cu" "F.Mask" "F.Paste")
			(net "GND")
		)
		(pad "G2" smd rect
			(at -21.874988 0 270)
			(size 2.5908 2.5908)
			(layers "F.Cu" "F.Mask" "F.Paste")
			(net "GND")
		)
		(pad "P1" smd rect
			(at 1.905 -1.82499 270)
			(size 0.6096 2.3622)
			(layers "F.Cu" "F.Mask" "F.Paste")
			(net "Net_2001")
		)
		(pad "P2" smd rect
			(at 0.635 -1.82499 270)
			(size 0.6096 2.3622)
			(layers "F.Cu" "F.Mask" "F.Paste")
			(net "Net_2002")
		)
		(pad "P3" smd rect
			(at -0.635 -1.82499 270)
			(size 0.6096 2.3622)
			(layers "F.Cu" "F.Mask" "F.Paste")
			(net "Net_2003")
		)
		(pad "P4" smd rect
			(at -1.905 -1.82499 270)
			(size 0.6096 2.3622)
			(layers "F.Cu" "F.Mask" "F.Paste")
			(net "GND")
		)
		(pad "P5" smd rect
			(at -3.175 -1.82499 270)
			(size 0.6096 2.3622)
			(layers "F.Cu" "F.Mask" "F.Paste")
			(net "HDD_PRSNT_8")
		)
		(pad "P6" smd rect
			(at -4.445 -1.82499 270)
			(size 0.6096 2.3622)
			(layers "F.Cu" "F.Mask" "F.Paste")
			(net "GND")
		)
		(pad "P7" smd rect
			(at -5.715 -1.82499 270)
			(size 0.6096 2.3622)
			(layers "F.Cu" "F.Mask" "F.Paste")
			(net "5V_PRE_8")
		)
		(pad "P8" smd rect
			(at -6.985 -1.82499 270)
			(size 0.6096 2.3622)
			(layers "F.Cu" "F.Mask" "F.Paste")
			(net "P5V_HDD8")
		)
		(pad "P9" smd rect
			(at -8.255 -1.82499 270)
			(size 0.6096 2.3622)
			(layers "F.Cu" "F.Mask" "F.Paste")
			(net "P5V_HDD8")
		)
		(pad "P10" smd rect
			(at -9.525 -1.82499 270)
			(size 0.6096 2.3622)
			(layers "F.Cu" "F.Mask" "F.Paste")
			(net "GND")
		)
		(pad "P11" smd rect
			(at -10.795 -1.82499 270)
			(size 0.6096 2.3622)
			(layers "F.Cu" "F.Mask" "F.Paste")
			(net "ACT_HDD_8")
		)
		(pad "P12" smd rect
			(at -12.065 -1.82499 270)
			(size 0.6096 2.3622)
			(layers "F.Cu" "F.Mask" "F.Paste")
			(net "GND")
		)
		(pad "P13" smd rect
			(at -13.335 -1.82499 270)
			(size 0.6096 2.3622)
			(layers "F.Cu" "F.Mask" "F.Paste")
			(net "12V_PRE_8")
		)
		(pad "P14" smd rect
			(at -14.605 -1.82499 270)
			(size 0.6096 2.3622)
			(layers "F.Cu" "F.Mask" "F.Paste")
			(net "P12V_HDD8")
		)
		(pad "P15" smd rect
			(at -15.875 -1.82499 270)
			(size 0.6096 2.3622)
			(layers "F.Cu" "F.Mask" "F.Paste")
			(net "P12V_HDD8")
		)
		(pad "S1" smd rect
			(at 15.875 -1.82499 270)
			(size 0.6096 2.3622)
			(layers "F.Cu" "F.Mask" "F.Paste")
			(net "GND")
		)
		(pad "S2" smd rect
			(at 14.605 -1.82499 270)
			(size 0.6096 2.3622)
			(layers "F.Cu" "F.Mask" "F.Paste")
			(net "SAS_HDD_RX_P8")
		)
		(pad "S3" smd rect
			(at 13.335 -1.82499 270)
			(size 0.6096 2.3622)
			(layers "F.Cu" "F.Mask" "F.Paste")
			(net "SAS_HDD_RX_N8")
		)
		(pad "S4" smd rect
			(at 12.065 -1.82499 270)
			(size 0.6096 2.3622)
			(layers "F.Cu" "F.Mask" "F.Paste")
			(net "GND")
		)
		(pad "S5" smd rect
			(at 10.795 -1.82499 270)
			(size 0.6096 2.3622)
			(layers "F.Cu" "F.Mask" "F.Paste")
			(net "PHY_DRV_A_TO_SCC_A_8_DN")
		)
		(pad "S6" smd rect
			(at 9.525 -1.82499 270)
			(size 0.6096 2.3622)
			(layers "F.Cu" "F.Mask" "F.Paste")
			(net "PHY_DRV_A_TO_SCC_A_8_DP")
		)
		(pad "S7" smd rect
			(at 8.255 -1.82499 270)
			(size 0.6096 2.3622)
			(layers "F.Cu" "F.Mask" "F.Paste")
			(net "GND")
		)
		(pad "S8" smd rect
			(at 7.480046 2.845054 270)
			(size 0.508 2.3622)
			(layers "F.Cu" "F.Mask" "F.Paste")
			(net "GND")
		)
		(pad "S9" smd rect
			(at 6.679946 2.845054 270)
			(size 0.508 2.3622)
			(layers "F.Cu" "F.Mask" "F.Paste")
			(net "Net_480")
		)
		(pad "S10" smd rect
			(at 5.8801 2.845054 270)
			(size 0.508 2.3622)
			(layers "F.Cu" "F.Mask" "F.Paste")
			(net "Net_372")
		)
		(pad "S11" smd rect
			(at 5.08 2.845054 270)
			(size 0.508 2.3622)
			(layers "F.Cu" "F.Mask" "F.Paste")
			(net "GND")
		)
		(pad "S12" smd rect
			(at 4.2799 2.845054 270)
			(size 0.508 2.3622)
			(layers "F.Cu" "F.Mask" "F.Paste")
			(net "Net_408")
		)
		(pad "S13" smd rect
			(at 3.480054 2.845054 270)
			(size 0.508 2.3622)
			(layers "F.Cu" "F.Mask" "F.Paste")
			(net "Net_444")
		)
		(pad "S14" smd rect
			(at 2.679954 2.845054 270)
			(size 0.508 2.3622)
			(layers "F.Cu" "F.Mask" "F.Paste")
			(net "GND")
		)
		(zone
			(layer "F.Cu")
			(hatch none 0.5)
			(connect_pads
				(clearance 0)
			)
			(min_thickness 0.25)
			(keepout
				(tracks not_allowed)
				(vias allowed)
				(pads allowed)
				(copperpour not_allowed)
				(footprints allowed)
			)
			(placement
				(enabled no)
				(sheetname "")
			)
			(fill
				(thermal_gap 0.5)
				(thermal_bridge_width 0.5)
				(island_removal_mode 0)
			)
			(polygon
				(pts
					(xy 392.307572 -304.648616) (xy 385.233672 -304.648616) (xy 385.233672 -311.582816) (xy 386.338572 -311.582816)
					(xy 386.338572 -307.468016) (xy 390.961372 -307.468016) (xy 390.961372 -311.582816) (xy 392.307572 -311.582816)
				)
			)
		)
		(zone
			(layer "F.Cu")
			(hatch none 0.5)
			(connect_pads
				(clearance 0)
			)
			(min_thickness 0.25)
			(keepout
				(tracks allowed)
				(vias not_allowed)
				(pads allowed)
				(copperpour not_allowed)
				(footprints allowed)
			)
			(placement
				(enabled no)
				(sheetname "")
			)
			(fill
				(thermal_gap 0.5)
				(thermal_bridge_width 0.5)
				(island_removal_mode 0)
			)
			(polygon
				(pts
					(xy 392.307572 -304.648616) (xy 385.233672 -304.648616) (xy 385.233672 -311.582816) (xy 386.338572 -311.582816)
					(xy 386.338572 -307.468016) (xy 390.961372 -307.468016) (xy 390.961372 -311.582816) (xy 392.307572 -311.582816)
				)
			)
		)
		(zone
			(layer "F.Cu")
			(hatch none 0.5)
			(connect_pads
				(clearance 0)
			)
			(min_thickness 0.25)
			(keepout
				(tracks not_allowed)
				(vias allowed)
				(pads allowed)
				(copperpour not_allowed)
				(footprints allowed)
			)
			(placement
				(enabled no)
				(sheetname "")
			)
			(fill
				(thermal_gap 0.5)
				(thermal_bridge_width 0.5)
				(island_removal_mode 0)
			)
			(polygon
				(pts
					(xy 392.307572 -271.171416) (xy 385.233672 -271.171416) (xy 385.233672 -264.237216) (xy 386.338572 -264.237216)
					(xy 386.338572 -268.352016) (xy 390.961372 -268.352016) (xy 390.961372 -264.237216) (xy 392.307572 -264.237216)
				)
			)
		)
		(zone
			(layer "F.Cu")
			(hatch none 0.5)
			(connect_pads
				(clearance 0)
			)
			(min_thickness 0.25)
			(keepout
				(tracks allowed)
				(vias not_allowed)
				(pads allowed)
				(copperpour not_allowed)
				(footprints allowed)
			)
			(placement
				(enabled no)
				(sheetname "")
			)
			(fill
				(thermal_gap 0.5)
				(thermal_bridge_width 0.5)
				(island_removal_mode 0)
			)
			(polygon
				(pts
					(xy 392.307572 -271.171416) (xy 385.233672 -271.171416) (xy 385.233672 -264.237216) (xy 386.338572 -264.237216)
					(xy 386.338572 -268.352016) (xy 390.961372 -268.352016) (xy 390.961372 -264.237216) (xy 392.307572 -264.237216)
				)
			)
		)
		(zone
			(layers "F.Cu" "B.Cu" "In1.Cu" "In2.Cu" "In3.Cu" "In4.Cu" "In5.Cu" "In6.Cu"
				"In7.Cu" "In8.Cu" "In9.Cu" "In10.Cu"
			)
			(hatch none 0.5)
			(connect_pads
				(clearance 0)
			)
			(min_thickness 0.25)
			(keepout
				(tracks not_allowed)
				(vias allowed)
				(pads allowed)
				(copperpour not_allowed)
				(footprints allowed)
			)
			(placement
				(enabled no)
				(sheetname "")
			)
			(fill
				(thermal_gap 0.5)
				(thermal_bridge_width 0.5)
				(island_removal_mode 0)
			)
			(polygon
				(pts
					(arc
						(start 389.424672 -269.035022)
						(mid 387.875272 -269.035022)
						(end 389.424672 -269.035022)
					)
				)
			)
		)
		(zone
			(layers "F.Cu" "B.Cu" "In1.Cu" "In2.Cu" "In3.Cu" "In4.Cu" "In5.Cu" "In6.Cu"
				"In7.Cu" "In8.Cu" "In9.Cu" "In10.Cu"
			)
			(hatch none 0.5)
			(connect_pads
				(clearance 0)
			)
			(min_thickness 0.25)
			(keepout
				(tracks not_allowed)
				(vias allowed)
				(pads allowed)
				(copperpour not_allowed)
				(footprints allowed)
			)
			(placement
				(enabled no)
				(sheetname "")
			)
			(fill
				(thermal_gap 0.5)
				(thermal_bridge_width 0.5)
				(island_removal_mode 0)
			)
			(polygon
				(pts
					(arc
						(start 389.627872 -306.78501)
						(mid 387.672072 -306.78501)
						(end 389.627872 -306.78501)
					)
				)
			)
		)
	)
	(footprint ""
		(layer "F.Cu")
		(at 235.809536 -343.301828)
		(property "Reference" "C63"
			(at 0 0 0)
			(layer "F.SilkS")
			(hide yes)
			(effects
				(font
					(size 1.27 1.27)
				)
			)
		)
		(property "Value" "SCD1U16V2KX-3GP"
			(at 1.1811 -2.7051 0)
			(unlocked yes)
			(layer "F.Fab")
			(hide yes)
			(effects
				(font
					(size 1.016 1.016)
					(thickness 0.1524)
				)
			)
		)
		(property "Device Type" "C402H22"
			(at 1.1811 -4.2291 0)
			(unlocked yes)
			(layer "F.Fab")
			(hide yes)
			(effects
				(font
					(size 1.016 1.016)
					(thickness 0.1524)
				)
			)
		)
		(duplicate_pad_numbers_are_jumpers no)
		(fp_rect
			(start -0.4318 0.9525)
			(end 0.4318 -0.9525)
			(stroke
				(width 0)
				(type default)
			)
			(fill no)
			(layer "F.CrtYd")
		)
		(fp_rect
			(start -0.4318 0.9525)
			(end 0.4318 -0.9525)
			(stroke
				(width 0)
				(type default)
			)
			(fill no)
			(layer "F.Fab")
		)
		(pad "1" smd custom
			(at 0 -0.4445)
			(size 0.1524 0.1524)
			(layers "F.Cu" "F.Mask" "F.Paste")
			(net "P5V_A_4_SENSE")
			(options
				(clearance outline)
				(anchor circle)
			)
			(primitives
				(gr_poly
					(pts
						(arc
							(start 0.3048 -0.2032)
							(mid 0.275042 -0.275042)
							(end 0.2032 -0.3048)
						)
						(arc
							(start -0.2032 -0.3048)
							(mid -0.275042 -0.275042)
							(end -0.3048 -0.2032)
						)
						(arc
							(start -0.3048 0.2032)
							(mid -0.275042 0.275042)
							(end -0.2032 0.3048)
						)
						(arc
							(start 0.2032 0.3048)
							(mid 0.275042 0.275042)
							(end 0.3048 0.2032)
						)
					)
					(width 0)
					(fill yes)
				)
			)
		)
		(pad "2" smd custom
			(at 0 0.4445)
			(size 0.1524 0.1524)
			(layers "F.Cu" "F.Mask" "F.Paste")
			(net "GND")
			(options
				(clearance outline)
				(anchor circle)
			)
			(primitives
				(gr_poly
					(pts
						(arc
							(start 0.3048 -0.2032)
							(mid 0.275042 -0.275042)
							(end 0.2032 -0.3048)
						)
						(arc
							(start -0.2032 -0.3048)
							(mid -0.275042 -0.275042)
							(end -0.3048 -0.2032)
						)
						(arc
							(start -0.3048 0.2032)
							(mid -0.275042 0.275042)
							(end -0.2032 0.3048)
						)
						(arc
							(start 0.2032 0.3048)
							(mid 0.275042 0.275042)
							(end 0.3048 0.2032)
						)
					)
					(width 0)
					(fill yes)
				)
			)
		)
	)
	(footprint ""
		(layer "F.Cu")
		(at 55.044848 -242.20297)
		(property "Reference" "R197"
			(at 0 0 0)
			(layer "F.SilkS")
			(hide yes)
			(effects
				(font
					(size 1.27 1.27)
				)
			)
		)
		(property "Value" "130R3F-GP"
			(at -0.0254 -2.5146 0)
			(unlocked yes)
			(layer "F.Fab")
			(hide yes)
			(effects
				(font
					(size 1.016 1.016)
					(thickness 0.1524)
				)
			)
		)
		(property "Device Type" "R603H22"
			(at -0.0254 -4.0386 0)
			(unlocked yes)
			(layer "F.Fab")
			(hide yes)
			(effects
				(font
					(size 1.016 1.016)
					(thickness 0.1524)
				)
			)
		)
		(duplicate_pad_numbers_are_jumpers no)
		(fp_line
			(start -0.4826 0)
			(end -0.2032 0)
			(stroke
				(width 0.2032)
				(type default)
			)
			(layer "F.SilkS")
		)
		(fp_line
			(start 0.2032 0)
			(end 0.4826 0)
			(stroke
				(width 0.2032)
				(type default)
			)
			(layer "F.SilkS")
		)
		(fp_rect
			(start -0.5842 1.3335)
			(end 0.5842 -1.3335)
			(stroke
				(width 0)
				(type default)
			)
			(fill no)
			(layer "F.CrtYd")
		)
		(fp_rect
			(start -0.5842 1.3335)
			(end 0.5842 -1.3335)
			(stroke
				(width 0)
				(type default)
			)
			(fill no)
			(layer "F.Fab")
		)
		(pad "1" smd custom
			(at 0 -0.762)
			(size 0.2159 0.2159)
			(layers "F.Cu" "F.Mask" "F.Paste")
			(net "P5V_A_1")
			(options
				(clearance outline)
				(anchor circle)
			)
			(primitives
				(gr_poly
					(pts
						(arc
							(start -0.3302 -0.4318)
							(mid -0.402042 -0.402042)
							(end -0.4318 -0.3302)
						)
						(arc
							(start -0.4318 0.3302)
							(mid -0.402042 0.402042)
							(end -0.3302 0.4318)
						)
						(arc
							(start 0.3302 0.4318)
							(mid 0.402042 0.402042)
							(end 0.4318 0.3302)
						)
						(arc
							(start 0.4318 -0.3302)
							(mid 0.402042 -0.402042)
							(end 0.3302 -0.4318)
						)
					)
					(width 0)
					(fill yes)
				)
			)
		)
		(pad "2" smd custom
			(at 0 0.762)
			(size 0.2159 0.2159)
			(layers "F.Cu" "F.Mask" "F.Paste")
			(net "FLT_HDD1")
			(options
				(clearance outline)
				(anchor circle)
			)
			(primitives
				(gr_poly
					(pts
						(arc
							(start -0.3302 -0.4318)
							(mid -0.402042 -0.402042)
							(end -0.4318 -0.3302)
						)
						(arc
							(start -0.4318 0.3302)
							(mid -0.402042 0.402042)
							(end -0.3302 0.4318)
						)
						(arc
							(start 0.3302 0.4318)
							(mid 0.402042 0.402042)
							(end 0.4318 0.3302)
						)
						(arc
							(start 0.4318 -0.3302)
							(mid 0.402042 -0.402042)
							(end 0.3302 -0.4318)
						)
					)
					(width 0)
					(fill yes)
				)
			)
		)
	)
)
